M48
INCH,TZ
T01C.008
T02C.01
T03C.012
T04C.01417
T05C.01456
T06C.016
T07C.02244
T08C.028
T09C.032
T010C.034
T011C.035
T012C.04
T013C.048
T014C.086
T015C.087
T016C.094
T017C.097
T018C.119
T019C.13
T020C.134
T021C.138
T022C.158
T023C.168
;EXTENTS: -105.403 -111.400 128.397 113.400 
;LEADER: 12 
;HEADER: 
;CODE  : ASCII 
;FILE  : 16318-2.rou for board 16318-2.brd
%
G90
F1
M16
T020
M16
G00X302552Y413583
G40
M15
G01X315952
M16
G00X83064Y238386
G40
M15
G01X96464
M16
T09
M16
G00X339331Y90729
G40
M15
G01Y93129
M16
G00X360669Y48602
G40
M15
G01Y51002
M16
G00X339331Y47252
G40
M15
G01Y52352
M16
G00X360669Y89379
G40
M15
G01Y94479
M16
G40
M30
